(kicad_pcb
	(version 20260206)
	(generator "pcbnew")
	(generator_version "10.0")
	(general
		(thickness 1.6)
		(legacy_teardrops no)
	)
	(paper "A4")
	(title_block
		(title "Bryce Canyon_IOM_IOC_16318-2_OCP.brd")
		(comment 1 "Bryce Canyon / footprints 359-359 of 1605")
	)
	(layers
		(0 "F.Cu" signal "TOP")
		(4 "In1.Cu" signal "L2GND")
		(6 "In2.Cu" signal "L3")
		(8 "In3.Cu" signal "L4VCC")
		(10 "In4.Cu" signal "L5VCC")
		(12 "In5.Cu" signal "L6")
		(14 "In6.Cu" signal "L7GND")
		(2 "B.Cu" signal "BOTTOM")
		(9 "F.Adhes" user "F.Adhesive")
		(11 "B.Adhes" user "B.Adhesive")
		(13 "F.Paste" user "Package Geometry/Pastemask Top")
		(15 "B.Paste" user "Package Geometry/Pastemask Bottom")
		(5 "F.SilkS" user "Ref Des/Silkscreen Top")
		(7 "B.SilkS" user "Ref Des/Silkscreen Bottom")
		(1 "F.Mask" user "Board Geometry/Soldermask Top")
		(3 "B.Mask" user "Board Geometry/Soldermask Bottom")
		(17 "Dwgs.User" user "User.Drawings")
		(19 "Cmts.User" user "User.Comments")
		(21 "Eco1.User" user "User.Eco1")
		(23 "Eco2.User" user "User.Eco2")
		(25 "Edge.Cuts" user "Board Geometry/Outline")
		(27 "Margin" user)
		(31 "F.CrtYd" user "Package Geometry/Place Bound Top")
		(29 "B.CrtYd" user "Package Geometry/Place Bound Bottom")
		(35 "F.Fab" user "Ref Des/Assembly Top")
		(33 "B.Fab" user "Ref Des/Assembly Bottom")
	)
	(footprint ""
		(layer "F.Cu")
		(at 46.035976 -119.346218 -90)
		(property "Reference" "R83"
			(at 0 0 270)
			(layer "F.SilkS")
			(hide yes)
			(effects
				(font
					(size 1.27 1.27)
				)
			)
		)
		(property "Value" "2K2R2J-2-GP"
			(at 0.064008 -3.993896 270)
			(unlocked yes)
			(layer "F.Fab")
			(hide yes)
			(effects
				(font
					(size 1.016 1.016)
					(thickness 0.1524)
				)
			)
		)
		(property "Device Type" "R402H16"
			(at 0.064008 -5.517896 270)
			(unlocked yes)
			(layer "F.Fab")
			(hide yes)
			(effects
				(font
					(size 1.016 1.016)
					(thickness 0.1524)
				)
			)
		)
		(duplicate_pad_numbers_are_jumpers no)
		(fp_line
			(start -0.508 -0.9398)
			(end -0.508 0.9398)
			(stroke
				(width 0.1524)
				(type default)
			)
			(layer "F.SilkS")
		)
		(fp_line
			(start 0.508 -0.9398)
			(end -0.508 -0.9398)
			(stroke
				(width 0.1524)
				(type default)
			)
			(layer "F.SilkS")
		)
		(fp_rect
			(start -0.508 0.9398)
			(end 0.508 -0.9398)
			(stroke
				(width 0)
				(type default)
			)
			(fill no)
			(layer "F.CrtYd")
		)
		(fp_rect
			(start -0.508 0.9398)
			(end 0.508 -0.9398)
			(stroke
				(width 0)
				(type default)
			)
			(fill no)
			(layer "F.Fab")
		)
		(pad "1" smd custom
			(at 0 -0.4445 270)
			(size 0.1397 0.1397)
			(layers "F.Cu" "F.Mask" "F.Paste")
			(net "P3V3_STBY")
			(options
				(clearance outline)
				(anchor circle)
			)
			(primitives
				(gr_poly
					(pts
						(arc
							(start -0.1778 -0.2794)
							(mid -0.249642 -0.249642)
							(end -0.2794 -0.1778)
						)
						(arc
							(start -0.2794 0.1778)
							(mid -0.249642 0.249642)
							(end -0.1778 0.2794)
						)
						(arc
							(start 0.1778 0.2794)
							(mid 0.249642 0.249642)
							(end 0.2794 0.1778)
						)
						(arc
							(start 0.2794 -0.1778)
							(mid 0.249642 -0.249642)
							(end 0.1778 -0.2794)
						)
					)
					(width 0)
					(fill yes)
				)
			)
		)
		(pad "2" smd custom
			(at 0 0.4445 270)
			(size 0.1397 0.1397)
			(layers "F.Cu" "F.Mask" "F.Paste")
			(net "FLA0_SPI_RST")
			(options
				(clearance outline)
				(anchor circle)
			)
			(primitives
				(gr_poly
					(pts
						(arc
							(start -0.1778 -0.2794)
							(mid -0.249642 -0.249642)
							(end -0.2794 -0.1778)
						)
						(arc
							(start -0.2794 0.1778)
							(mid -0.249642 0.249642)
							(end -0.1778 0.2794)
						)
						(arc
							(start 0.1778 0.2794)
							(mid 0.249642 0.249642)
							(end 0.2794 0.1778)
						)
						(arc
							(start 0.2794 -0.1778)
							(mid 0.249642 -0.249642)
							(end 0.1778 -0.2794)
						)
					)
					(width 0)
					(fill yes)
				)
			)
		)
	)
)
